(kicad_pcb
	(version 20260206)
	(generator "pcbnew")
	(generator_version "10.0")
	(general
		(thickness 1.6)
		(legacy_teardrops no)
	)
	(paper "A4")
	(title_block
		(title "04192023_DAF0TMB3IC0_F0TG_MB_C_brd_V02_OCP.brd")
		(comment 1 "Grand Teton / footprints 3335-3341 of 8354")
	)
	(layers
		(0 "F.Cu" signal "TOP")
		(4 "In1.Cu" signal "GND")
		(6 "In2.Cu" signal "IN1")
		(8 "In3.Cu" signal "GND1")
		(10 "In4.Cu" signal "IN2")
		(12 "In5.Cu" signal "GND2")
		(14 "In6.Cu" signal "IN3")
		(16 "In7.Cu" signal "GND3")
		(18 "In8.Cu" signal "VCC")
		(20 "In9.Cu" signal "VCC1")
		(22 "In10.Cu" signal "GND4")
		(24 "In11.Cu" signal "IN4")
		(26 "In12.Cu" signal "GND5")
		(28 "In13.Cu" signal "IN5")
		(30 "In14.Cu" signal "GND6")
		(32 "In15.Cu" signal "IN6")
		(34 "In16.Cu" signal "GND7")
		(2 "B.Cu" signal "BOTTOM")
		(9 "F.Adhes" user "F.Adhesive")
		(11 "B.Adhes" user "B.Adhesive")
		(13 "F.Paste" user "Package Geometry/Pastemask Top")
		(15 "B.Paste" user "Package Geometry/Pastemask Bottom")
		(5 "F.SilkS" user "Ref Des/Silkscreen Top")
		(7 "B.SilkS" user "Ref Des/Silkscreen Bottom")
		(1 "F.Mask" user "Board Geometry/Soldermask Top")
		(3 "B.Mask" user "Board Geometry/Soldermask Bottom")
		(17 "Dwgs.User" user "User.Drawings")
		(19 "Cmts.User" user "User.Comments")
		(21 "Eco1.User" user "User.Eco1")
		(23 "Eco2.User" user "User.Eco2")
		(25 "Edge.Cuts" user "Board Geometry/Outline")
		(27 "Margin" user)
		(31 "F.CrtYd" user "Package Geometry/Place Bound Top")
		(29 "B.CrtYd" user "Package Geometry/Place Bound Bottom")
		(35 "F.Fab" user "Ref Des/Assembly Top")
		(33 "B.Fab" user "Ref Des/Assembly Bottom")
	)
	(footprint ""
		(layer "F.Cu")
		(at 203.573126 -344.92692)
		(property "Reference" "PC123"
			(at 0 0 0)
			(layer "F.SilkS")
			(hide yes)
			(effects
				(font
					(size 1.27 1.27)
				)
			)
		)
		(property "Value" ""
			(at 0 0 0)
			(layer "F.Fab")
			(effects
				(font
					(size 1.27 1.27)
				)
			)
		)
		(duplicate_pad_numbers_are_jumpers no)
		(fp_line
			(start -1.524 -0.762)
			(end 1.524 -0.762)
			(stroke
				(width 0.1524)
				(type default)
			)
			(layer "F.SilkS")
		)
		(fp_line
			(start -1.524 0.762)
			(end -1.524 -0.762)
			(stroke
				(width 0.1524)
				(type default)
			)
			(layer "F.SilkS")
		)
		(fp_line
			(start 1.524 -0.762)
			(end 1.524 0.762)
			(stroke
				(width 0.1524)
				(type default)
			)
			(layer "F.SilkS")
		)
		(fp_line
			(start 1.524 0.762)
			(end -1.524 0.762)
			(stroke
				(width 0.1524)
				(type default)
			)
			(layer "F.SilkS")
		)
		(fp_line
			(start -1.1049 -0.724916)
			(end -1.1049 0.724916)
			(stroke
				(width 0.1)
				(type default)
			)
			(layer "F.Fab")
		)
		(fp_line
			(start -1.1049 0.724916)
			(end 1.1049 0.724916)
			(stroke
				(width 0.1)
				(type default)
			)
			(layer "F.Fab")
		)
		(fp_line
			(start 1.1049 -0.724916)
			(end -1.1049 -0.724916)
			(stroke
				(width 0.1)
				(type default)
			)
			(layer "F.Fab")
		)
		(fp_line
			(start 1.1049 0.724916)
			(end 1.1049 -0.724916)
			(stroke
				(width 0.1)
				(type default)
			)
			(layer "F.Fab")
		)
		(pad "1" smd rect
			(at -0.889 0 180)
			(size 1.016 1.27)
			(layers "F.Cu" "F.Mask" "F.Paste")
			(net "SW_P12V_AUX_PVDD_33_S5_FLT")
		)
		(pad "2" smd rect
			(at 0.889 0 180)
			(size 1.016 1.27)
			(layers "F.Cu" "F.Mask" "F.Paste")
			(net "GND")
		)
	)
	(footprint ""
		(layer "F.Cu")
		(at 270.48841 -332.609952 90)
		(property "Reference" "PC107"
			(at 0 0 90)
			(layer "F.SilkS")
			(hide yes)
			(effects
				(font
					(size 1.27 1.27)
				)
			)
		)
		(property "Value" ""
			(at 0 0 90)
			(layer "F.Fab")
			(effects
				(font
					(size 1.27 1.27)
				)
			)
		)
		(duplicate_pad_numbers_are_jumpers no)
		(fp_line
			(start 0.7874 -0.4064)
			(end 0.7874 0.4064)
			(stroke
				(width 0.1524)
				(type default)
			)
			(layer "F.SilkS")
		)
		(fp_line
			(start -0.7874 -0.4064)
			(end 0.7874 -0.4064)
			(stroke
				(width 0.1524)
				(type default)
			)
			(layer "F.SilkS")
		)
		(fp_line
			(start 0.7874 0.4064)
			(end -0.7874 0.4064)
			(stroke
				(width 0.1524)
				(type default)
			)
			(layer "F.SilkS")
		)
		(fp_line
			(start -0.7874 0.4064)
			(end -0.7874 -0.4064)
			(stroke
				(width 0.1524)
				(type default)
			)
			(layer "F.SilkS")
		)
		(fp_line
			(start -0.12065 -0.305054)
			(end -0.12065 -0.2794)
			(stroke
				(width 0.1)
				(type default)
			)
			(layer "F.Fab")
		)
		(fp_line
			(start -0.67945 -0.305054)
			(end -0.12065 -0.305054)
			(stroke
				(width 0.1)
				(type default)
			)
			(layer "F.Fab")
		)
		(fp_line
			(start 0.67945 -0.3048)
			(end 0.67945 0.3048)
			(stroke
				(width 0.1)
				(type default)
			)
			(layer "F.Fab")
		)
		(fp_line
			(start 0.12065 -0.3048)
			(end 0.67945 -0.3048)
			(stroke
				(width 0.1)
				(type default)
			)
			(layer "F.Fab")
		)
		(fp_line
			(start 0.12065 -0.2794)
			(end 0.12065 -0.3048)
			(stroke
				(width 0.1)
				(type default)
			)
			(layer "F.Fab")
		)
		(fp_line
			(start -0.12065 -0.2794)
			(end 0.12065 -0.2794)
			(stroke
				(width 0.1)
				(type default)
			)
			(layer "F.Fab")
		)
		(fp_line
			(start 0.120396 0.2794)
			(end -0.12065 0.2794)
			(stroke
				(width 0.1)
				(type default)
			)
			(layer "F.Fab")
		)
		(fp_line
			(start -0.12065 0.2794)
			(end -0.12065 0.3048)
			(stroke
				(width 0.1)
				(type default)
			)
			(layer "F.Fab")
		)
		(fp_line
			(start 0.67945 0.3048)
			(end 0.120396 0.3048)
			(stroke
				(width 0.1)
				(type default)
			)
			(layer "F.Fab")
		)
		(fp_line
			(start 0.120396 0.3048)
			(end 0.120396 0.2794)
			(stroke
				(width 0.1)
				(type default)
			)
			(layer "F.Fab")
		)
		(fp_line
			(start -0.12065 0.3048)
			(end -0.67945 0.3048)
			(stroke
				(width 0.1)
				(type default)
			)
			(layer "F.Fab")
		)
		(fp_line
			(start -0.67945 0.3048)
			(end -0.67945 -0.305054)
			(stroke
				(width 0.1)
				(type default)
			)
			(layer "F.Fab")
		)
		(pad "1" smd circle
			(at -0.40005 0 90)
			(size 0 0)
			(layers "F.Cu" "F.Mask" "F.Paste")
			(net "PVDDIO_P0")
		)
		(pad "2" smd circle
			(at 0.40005 0 90)
			(size 0 0)
			(layers "F.Cu" "F.Mask" "F.Paste")
			(net "GND")
		)
	)
	(footprint ""
		(layer "F.Cu")
		(at 416.817302 -416.899344 -90)
		(property "Reference" "C6596"
			(at 0 0 270)
			(layer "F.SilkS")
			(hide yes)
			(effects
				(font
					(size 1.27 1.27)
				)
			)
		)
		(property "Value" ""
			(at 0 0 270)
			(layer "F.Fab")
			(effects
				(font
					(size 1.27 1.27)
				)
			)
		)
		(duplicate_pad_numbers_are_jumpers no)
		(fp_line
			(start -0.299974 0.150114)
			(end -0.299974 -0.150114)
			(stroke
				(width 0.1)
				(type default)
			)
			(layer "F.Fab")
		)
		(fp_line
			(start 0.299974 0.150114)
			(end -0.299974 0.150114)
			(stroke
				(width 0.1)
				(type default)
			)
			(layer "F.Fab")
		)
		(fp_line
			(start -0.299974 -0.150114)
			(end 0.299974 -0.150114)
			(stroke
				(width 0.1)
				(type default)
			)
			(layer "F.Fab")
		)
		(fp_line
			(start 0.299974 -0.150114)
			(end 0.299974 0.150114)
			(stroke
				(width 0.1)
				(type default)
			)
			(layer "F.Fab")
		)
		(pad "1" smd rect
			(at -0.2667 0 270)
			(size 0.3048 0.381)
			(layers "F.Cu" "F.Mask" "F.Paste")
			(net "P5E_CPU0_P2_TX_BUF_C_DN<15>")
		)
		(pad "2" smd rect
			(at 0.2667 0 270)
			(size 0.3048 0.381)
			(layers "F.Cu" "F.Mask" "F.Paste")
			(net "P5E_CPU0_P2_TX_BUF_DN<15>")
		)
	)
	(footprint ""
		(layer "F.Cu")
		(at 393.795758 -147.663662 -90)
		(property "Reference" "PJ1"
			(at 2.030476 0.681228 0)
			(unlocked yes)
			(layer "F.SilkS")
			(effects
				(font
					(size 0.7874 0.5842)
					(thickness 0.1524)
				)
				(justify left)
			)
		)
		(property "Value" ""
			(at 0 0 270)
			(layer "F.Fab")
			(effects
				(font
					(size 1.27 1.27)
				)
			)
		)
		(duplicate_pad_numbers_are_jumpers no)
		(fp_line
			(start -1.249934 6.400038)
			(end -1.249934 -1.320038)
			(stroke
				(width 0.1524)
				(type default)
			)
			(layer "F.SilkS")
		)
		(fp_line
			(start 1.249934 6.400038)
			(end -1.249934 6.400038)
			(stroke
				(width 0.1524)
				(type default)
			)
			(layer "F.SilkS")
		)
		(fp_line
			(start -1.249934 -1.320038)
			(end 1.249934 -1.320038)
			(stroke
				(width 0.1524)
				(type default)
			)
			(layer "F.SilkS")
		)
		(fp_line
			(start 1.249934 -1.320038)
			(end 1.249934 6.400038)
			(stroke
				(width 0.1524)
				(type default)
			)
			(layer "F.SilkS")
		)
		(fp_poly
			(pts
				(xy -2.5654 -0.556514) (xy -1.452372 0) (xy -2.5654 0.556514)
			)
			(stroke
				(width 0)
				(type default)
			)
			(fill yes)
			(layer "F.SilkS")
		)
		(fp_line
			(start -1.249934 6.400038)
			(end -1.249934 -1.320038)
			(stroke
				(width 0.1)
				(type default)
			)
			(layer "F.Fab")
		)
		(fp_line
			(start 1.249934 6.400038)
			(end -1.249934 6.400038)
			(stroke
				(width 0.1)
				(type default)
			)
			(layer "F.Fab")
		)
		(fp_line
			(start -1.249934 -1.320038)
			(end 1.249934 -1.320038)
			(stroke
				(width 0.1)
				(type default)
			)
			(layer "F.Fab")
		)
		(fp_line
			(start 1.249934 -1.320038)
			(end 1.249934 6.400038)
			(stroke
				(width 0.1)
				(type default)
			)
			(layer "F.Fab")
		)
		(fp_poly
			(pts
				(xy -2.5654 -0.556514) (xy -1.452372 0) (xy -2.5654 0.556514)
			)
			(stroke
				(width 0)
				(type default)
			)
			(fill yes)
			(layer "F.Fab")
		)
		(fp_text user "3"
			(at -2.003806 5.113528 0)
			(unlocked yes)
			(layer "F.SilkS")
			(effects
				(font
					(size 0.7874 0.5842)
					(thickness 0.1524)
				)
			)
		)
		(fp_text user "3"
			(at -1.1557 5.18287 270)
			(unlocked yes)
			(layer "B.SilkS")
			(effects
				(font
					(size 0.7874 0.5842)
					(thickness 0.1524)
				)
				(justify mirror)
			)
		)
		(fp_text user "1"
			(at -1.143 0.02667 270)
			(unlocked yes)
			(layer "B.SilkS")
			(effects
				(font
					(size 0.7874 0.5842)
					(thickness 0.1524)
				)
				(justify mirror)
			)
		)
		(fp_text user "3"
			(at -1.1557 5.18287 270)
			(unlocked yes)
			(layer "B.Fab")
			(effects
				(font
					(size 0.7874 0.5842)
					(thickness 0.1524)
				)
				(justify mirror)
			)
		)
		(fp_text user "1"
			(at -1.143 0.02667 270)
			(unlocked yes)
			(layer "B.Fab")
			(effects
				(font
					(size 0.7874 0.5842)
					(thickness 0.1524)
				)
				(justify mirror)
			)
		)
		(fp_text user "3"
			(at -1.778 5.13207 270)
			(unlocked yes)
			(layer "F.Fab")
			(effects
				(font
					(size 0.7874 0.5842)
					(thickness 0.1524)
				)
			)
		)
		(pad "1" thru_hole rect
			(at 0 0 270)
			(size 1.5494 1.5494)
			(drill 1.0414)
			(layers "*.Cu" "*.Mask")
			(remove_unused_layers no)
			(net "GND")
			(clearance 0)
			(padstack
				(mode front_inner_back)
				(layer "Inner"
					(shape circle)
					(size 1.5494 1.5494)
					(clearance 0)
				)
				(layer "B.Cu"
					(shape rect)
					(size 1.5494 1.5494)
					(clearance 0)
				)
			)
		)
		(pad "2" thru_hole circle
			(at 0 2.54 270)
			(size 1.5494 1.5494)
			(drill 1.0414)
			(layers "*.Cu" "*.Mask")
			(remove_unused_layers no)
			(net "SMB_SCM_2_R3_SDA")
			(clearance 0)
		)
		(pad "3" thru_hole circle
			(at 0 5.08 270)
			(size 1.5494 1.5494)
			(drill 1.0414)
			(layers "*.Cu" "*.Mask")
			(remove_unused_layers no)
			(net "SMB_SCM_2_R3_SCL")
			(clearance 0)
		)
	)
	(footprint ""
		(layer "F.Cu")
		(at 393.363196 -321.632834)
		(property "Reference" "R582"
			(at 0 0 0)
			(layer "F.SilkS")
			(hide yes)
			(effects
				(font
					(size 1.27 1.27)
				)
			)
		)
		(property "Value" ""
			(at 0 0 0)
			(layer "F.Fab")
			(effects
				(font
					(size 1.27 1.27)
				)
			)
		)
		(duplicate_pad_numbers_are_jumpers no)
		(fp_line
			(start -0.7874 -0.4064)
			(end 0.7874 -0.4064)
			(stroke
				(width 0.1524)
				(type default)
			)
			(layer "F.SilkS")
		)
		(fp_line
			(start -0.7874 0.4064)
			(end -0.7874 -0.4064)
			(stroke
				(width 0.1524)
				(type default)
			)
			(layer "F.SilkS")
		)
		(fp_line
			(start 0.7874 -0.4064)
			(end 0.7874 0.4064)
			(stroke
				(width 0.1524)
				(type default)
			)
			(layer "F.SilkS")
		)
		(fp_line
			(start 0.7874 0.4064)
			(end -0.7874 0.4064)
			(stroke
				(width 0.1524)
				(type default)
			)
			(layer "F.SilkS")
		)
		(fp_line
			(start -0.67945 -0.305054)
			(end -0.12065 -0.305054)
			(stroke
				(width 0.1)
				(type default)
			)
			(layer "F.Fab")
		)
		(fp_line
			(start -0.67945 0.3048)
			(end -0.67945 -0.305054)
			(stroke
				(width 0.1)
				(type default)
			)
			(layer "F.Fab")
		)
		(fp_line
			(start -0.12065 -0.305054)
			(end -0.12065 -0.2794)
			(stroke
				(width 0.1)
				(type default)
			)
			(layer "F.Fab")
		)
		(fp_line
			(start -0.12065 -0.2794)
			(end 0.12065 -0.2794)
			(stroke
				(width 0.1)
				(type default)
			)
			(layer "F.Fab")
		)
		(fp_line
			(start -0.12065 0.2794)
			(end -0.12065 0.3048)
			(stroke
				(width 0.1)
				(type default)
			)
			(layer "F.Fab")
		)
		(fp_line
			(start -0.12065 0.3048)
			(end -0.67945 0.3048)
			(stroke
				(width 0.1)
				(type default)
			)
			(layer "F.Fab")
		)
		(fp_line
			(start 0.120396 0.2794)
			(end -0.12065 0.2794)
			(stroke
				(width 0.1)
				(type default)
			)
			(layer "F.Fab")
		)
		(fp_line
			(start 0.120396 0.3048)
			(end 0.120396 0.2794)
			(stroke
				(width 0.1)
				(type default)
			)
			(layer "F.Fab")
		)
		(fp_line
			(start 0.12065 -0.3048)
			(end 0.67945 -0.3048)
			(stroke
				(width 0.1)
				(type default)
			)
			(layer "F.Fab")
		)
		(fp_line
			(start 0.12065 -0.2794)
			(end 0.12065 -0.3048)
			(stroke
				(width 0.1)
				(type default)
			)
			(layer "F.Fab")
		)
		(fp_line
			(start 0.67945 -0.3048)
			(end 0.67945 0.3048)
			(stroke
				(width 0.1)
				(type default)
			)
			(layer "F.Fab")
		)
		(fp_line
			(start 0.67945 0.3048)
			(end 0.120396 0.3048)
			(stroke
				(width 0.1)
				(type default)
			)
			(layer "F.Fab")
		)
		(pad "1" smd circle
			(at -0.40005 0)
			(size 0 0)
			(layers "F.Cu" "F.Mask" "F.Paste")
			(net "GND")
		)
		(pad "2" smd circle
			(at 0.40005 0)
			(size 0 0)
			(layers "F.Cu" "F.Mask" "F.Paste")
			(net "RST_CPU0_RSMRST_N")
		)
	)
	(footprint ""
		(layer "F.Cu")
		(at 68.341494 -164.071046 -90)
		(property "Reference" "PC124_6"
			(at 0 0 270)
			(layer "F.SilkS")
			(hide yes)
			(effects
				(font
					(size 1.27 1.27)
				)
			)
		)
		(property "Value" ""
			(at 0 0 270)
			(layer "F.Fab")
			(effects
				(font
					(size 1.27 1.27)
				)
			)
		)
		(duplicate_pad_numbers_are_jumpers no)
		(fp_line
			(start -0.7874 0.4064)
			(end -0.7874 -0.4064)
			(stroke
				(width 0.1524)
				(type default)
			)
			(layer "F.SilkS")
		)
		(fp_line
			(start 0.7874 0.4064)
			(end -0.7874 0.4064)
			(stroke
				(width 0.1524)
				(type default)
			)
			(layer "F.SilkS")
		)
		(fp_line
			(start -0.7874 -0.4064)
			(end 0.7874 -0.4064)
			(stroke
				(width 0.1524)
				(type default)
			)
			(layer "F.SilkS")
		)
		(fp_line
			(start 0.7874 -0.4064)
			(end 0.7874 0.4064)
			(stroke
				(width 0.1524)
				(type default)
			)
			(layer "F.SilkS")
		)
		(fp_line
			(start -0.67945 0.3048)
			(end -0.67945 -0.305054)
			(stroke
				(width 0.1)
				(type default)
			)
			(layer "F.Fab")
		)
		(fp_line
			(start -0.12065 0.3048)
			(end -0.67945 0.3048)
			(stroke
				(width 0.1)
				(type default)
			)
			(layer "F.Fab")
		)
		(fp_line
			(start 0.120396 0.3048)
			(end 0.120396 0.2794)
			(stroke
				(width 0.1)
				(type default)
			)
			(layer "F.Fab")
		)
		(fp_line
			(start 0.67945 0.3048)
			(end 0.120396 0.3048)
			(stroke
				(width 0.1)
				(type default)
			)
			(layer "F.Fab")
		)
		(fp_line
			(start -0.12065 0.2794)
			(end -0.12065 0.3048)
			(stroke
				(width 0.1)
				(type default)
			)
			(layer "F.Fab")
		)
		(fp_line
			(start 0.120396 0.2794)
			(end -0.12065 0.2794)
			(stroke
				(width 0.1)
				(type default)
			)
			(layer "F.Fab")
		)
		(fp_line
			(start -0.12065 -0.2794)
			(end 0.12065 -0.2794)
			(stroke
				(width 0.1)
				(type default)
			)
			(layer "F.Fab")
		)
		(fp_line
			(start 0.12065 -0.2794)
			(end 0.12065 -0.3048)
			(stroke
				(width 0.1)
				(type default)
			)
			(layer "F.Fab")
		)
		(fp_line
			(start 0.12065 -0.3048)
			(end 0.67945 -0.3048)
			(stroke
				(width 0.1)
				(type default)
			)
			(layer "F.Fab")
		)
		(fp_line
			(start 0.67945 -0.3048)
			(end 0.67945 0.3048)
			(stroke
				(width 0.1)
				(type default)
			)
			(layer "F.Fab")
		)
		(fp_line
			(start -0.67945 -0.305054)
			(end -0.12065 -0.305054)
			(stroke
				(width 0.1)
				(type default)
			)
			(layer "F.Fab")
		)
		(fp_line
			(start -0.12065 -0.305054)
			(end -0.12065 -0.2794)
			(stroke
				(width 0.1)
				(type default)
			)
			(layer "F.Fab")
		)
		(pad "1" smd circle
			(at -0.40005 0 270)
			(size 0 0)
			(layers "F.Cu" "F.Mask" "F.Paste")
			(net "PVDDCR_CPU0_P1_VCCS")
		)
		(pad "2" smd circle
			(at 0.40005 0 270)
			(size 0 0)
			(layers "F.Cu" "F.Mask" "F.Paste")
			(net "GND")
		)
	)
	(footprint ""
		(layer "F.Cu")
		(at 185.928762 -25.899872 180)
		(property "Reference" "PR4004"
			(at 0 0 180)
			(layer "F.SilkS")
			(hide yes)
			(effects
				(font
					(size 1.27 1.27)
				)
			)
		)
		(property "Value" ""
			(at 0 0 180)
			(layer "F.Fab")
			(effects
				(font
					(size 1.27 1.27)
				)
			)
		)
		(duplicate_pad_numbers_are_jumpers no)
		(fp_line
			(start 0.7874 0.4064)
			(end -0.7874 0.4064)
			(stroke
				(width 0.1524)
				(type default)
			)
			(layer "F.SilkS")
		)
		(fp_line
			(start 0.7874 -0.4064)
			(end 0.7874 0.4064)
			(stroke
				(width 0.1524)
				(type default)
			)
			(layer "F.SilkS")
		)
		(fp_line
			(start -0.7874 0.4064)
			(end -0.7874 -0.4064)
			(stroke
				(width 0.1524)
				(type default)
			)
			(layer "F.SilkS")
		)
		(fp_line
			(start -0.7874 -0.4064)
			(end 0.7874 -0.4064)
			(stroke
				(width 0.1524)
				(type default)
			)
			(layer "F.SilkS")
		)
		(fp_line
			(start 0.67945 0.3048)
			(end 0.120396 0.3048)
			(stroke
				(width 0.1)
				(type default)
			)
			(layer "F.Fab")
		)
		(fp_line
			(start 0.67945 -0.3048)
			(end 0.67945 0.3048)
			(stroke
				(width 0.1)
				(type default)
			)
			(layer "F.Fab")
		)
		(fp_line
			(start 0.12065 -0.2794)
			(end 0.12065 -0.3048)
			(stroke
				(width 0.1)
				(type default)
			)
			(layer "F.Fab")
		)
		(fp_line
			(start 0.12065 -0.3048)
			(end 0.67945 -0.3048)
			(stroke
				(width 0.1)
				(type default)
			)
			(layer "F.Fab")
		)
		(fp_line
			(start 0.120396 0.3048)
			(end 0.120396 0.2794)
			(stroke
				(width 0.1)
				(type default)
			)
			(layer "F.Fab")
		)
		(fp_line
			(start 0.120396 0.2794)
			(end -0.12065 0.2794)
			(stroke
				(width 0.1)
				(type default)
			)
			(layer "F.Fab")
		)
		(fp_line
			(start -0.12065 0.3048)
			(end -0.67945 0.3048)
			(stroke
				(width 0.1)
				(type default)
			)
			(layer "F.Fab")
		)
		(fp_line
			(start -0.12065 0.2794)
			(end -0.12065 0.3048)
			(stroke
				(width 0.1)
				(type default)
			)
			(layer "F.Fab")
		)
		(fp_line
			(start -0.12065 -0.2794)
			(end 0.12065 -0.2794)
			(stroke
				(width 0.1)
				(type default)
			)
			(layer "F.Fab")
		)
		(fp_line
			(start -0.12065 -0.305054)
			(end -0.12065 -0.2794)
			(stroke
				(width 0.1)
				(type default)
			)
			(layer "F.Fab")
		)
		(fp_line
			(start -0.67945 0.3048)
			(end -0.67945 -0.305054)
			(stroke
				(width 0.1)
				(type default)
			)
			(layer "F.Fab")
		)
		(fp_line
			(start -0.67945 -0.305054)
			(end -0.12065 -0.305054)
			(stroke
				(width 0.1)
				(type default)
			)
			(layer "F.Fab")
		)
		(pad "1" smd circle
			(at -0.40005 0 180)
			(size 0 0)
			(layers "F.Cu" "F.Mask" "F.Paste")
			(net "P12V_SCM_CB")
		)
		(pad "2" smd circle
			(at 0.40005 0 180)
			(size 0 0)
			(layers "F.Cu" "F.Mask" "F.Paste")
			(net "GND")
		)
	)
)
